(kicad_pcb
	(version 20260206)
	(generator "pcbnew")
	(generator_version "10.0")
	(general
		(thickness 1.6)
		(legacy_teardrops no)
	)
	(paper "A4")
	(title_block
		(title "04192023_DAF0TMB3IC0_F0TG_MB_C_brd_V02_OCP.brd")
		(comment 1 "Grand Teton / footprints 3349-3354 of 8354")
	)
	(layers
		(0 "F.Cu" signal "TOP")
		(4 "In1.Cu" signal "GND")
		(6 "In2.Cu" signal "IN1")
		(8 "In3.Cu" signal "GND1")
		(10 "In4.Cu" signal "IN2")
		(12 "In5.Cu" signal "GND2")
		(14 "In6.Cu" signal "IN3")
		(16 "In7.Cu" signal "GND3")
		(18 "In8.Cu" signal "VCC")
		(20 "In9.Cu" signal "VCC1")
		(22 "In10.Cu" signal "GND4")
		(24 "In11.Cu" signal "IN4")
		(26 "In12.Cu" signal "GND5")
		(28 "In13.Cu" signal "IN5")
		(30 "In14.Cu" signal "GND6")
		(32 "In15.Cu" signal "IN6")
		(34 "In16.Cu" signal "GND7")
		(2 "B.Cu" signal "BOTTOM")
		(9 "F.Adhes" user "F.Adhesive")
		(11 "B.Adhes" user "B.Adhesive")
		(13 "F.Paste" user "Package Geometry/Pastemask Top")
		(15 "B.Paste" user "Package Geometry/Pastemask Bottom")
		(5 "F.SilkS" user "Ref Des/Silkscreen Top")
		(7 "B.SilkS" user "Ref Des/Silkscreen Bottom")
		(1 "F.Mask" user "Board Geometry/Soldermask Top")
		(3 "B.Mask" user "Board Geometry/Soldermask Bottom")
		(17 "Dwgs.User" user "User.Drawings")
		(19 "Cmts.User" user "User.Comments")
		(21 "Eco1.User" user "User.Eco1")
		(23 "Eco2.User" user "User.Eco2")
		(25 "Edge.Cuts" user "Board Geometry/Outline")
		(27 "Margin" user)
		(31 "F.CrtYd" user "Package Geometry/Place Bound Top")
		(29 "B.CrtYd" user "Package Geometry/Place Bound Bottom")
		(35 "F.Fab" user "Ref Des/Assembly Top")
		(33 "B.Fab" user "Ref Des/Assembly Bottom")
	)
	(footprint ""
		(layer "F.Cu")
		(at 115.08359 -417.939982 90)
		(property "Reference" "R3028"
			(at 0 0 90)
			(layer "F.SilkS")
			(hide yes)
			(effects
				(font
					(size 1.27 1.27)
				)
			)
		)
		(property "Value" ""
			(at 0 0 90)
			(layer "F.Fab")
			(effects
				(font
					(size 1.27 1.27)
				)
			)
		)
		(duplicate_pad_numbers_are_jumpers no)
		(fp_line
			(start 0.7874 -0.4064)
			(end 0.7874 0.4064)
			(stroke
				(width 0.1524)
				(type default)
			)
			(layer "F.SilkS")
		)
		(fp_line
			(start -0.7874 -0.4064)
			(end 0.7874 -0.4064)
			(stroke
				(width 0.1524)
				(type default)
			)
			(layer "F.SilkS")
		)
		(fp_line
			(start 0.7874 0.4064)
			(end -0.7874 0.4064)
			(stroke
				(width 0.1524)
				(type default)
			)
			(layer "F.SilkS")
		)
		(fp_line
			(start -0.7874 0.4064)
			(end -0.7874 -0.4064)
			(stroke
				(width 0.1524)
				(type default)
			)
			(layer "F.SilkS")
		)
		(fp_line
			(start -0.12065 -0.305054)
			(end -0.12065 -0.2794)
			(stroke
				(width 0.1)
				(type default)
			)
			(layer "F.Fab")
		)
		(fp_line
			(start -0.67945 -0.305054)
			(end -0.12065 -0.305054)
			(stroke
				(width 0.1)
				(type default)
			)
			(layer "F.Fab")
		)
		(fp_line
			(start 0.67945 -0.3048)
			(end 0.67945 0.3048)
			(stroke
				(width 0.1)
				(type default)
			)
			(layer "F.Fab")
		)
		(fp_line
			(start 0.12065 -0.3048)
			(end 0.67945 -0.3048)
			(stroke
				(width 0.1)
				(type default)
			)
			(layer "F.Fab")
		)
		(fp_line
			(start 0.12065 -0.2794)
			(end 0.12065 -0.3048)
			(stroke
				(width 0.1)
				(type default)
			)
			(layer "F.Fab")
		)
		(fp_line
			(start -0.12065 -0.2794)
			(end 0.12065 -0.2794)
			(stroke
				(width 0.1)
				(type default)
			)
			(layer "F.Fab")
		)
		(fp_line
			(start 0.120396 0.2794)
			(end -0.12065 0.2794)
			(stroke
				(width 0.1)
				(type default)
			)
			(layer "F.Fab")
		)
		(fp_line
			(start -0.12065 0.2794)
			(end -0.12065 0.3048)
			(stroke
				(width 0.1)
				(type default)
			)
			(layer "F.Fab")
		)
		(fp_line
			(start 0.67945 0.3048)
			(end 0.120396 0.3048)
			(stroke
				(width 0.1)
				(type default)
			)
			(layer "F.Fab")
		)
		(fp_line
			(start 0.120396 0.3048)
			(end 0.120396 0.2794)
			(stroke
				(width 0.1)
				(type default)
			)
			(layer "F.Fab")
		)
		(fp_line
			(start -0.12065 0.3048)
			(end -0.67945 0.3048)
			(stroke
				(width 0.1)
				(type default)
			)
			(layer "F.Fab")
		)
		(fp_line
			(start -0.67945 0.3048)
			(end -0.67945 -0.305054)
			(stroke
				(width 0.1)
				(type default)
			)
			(layer "F.Fab")
		)
		(pad "1" smd circle
			(at -0.40005 0 90)
			(size 0 0)
			(layers "F.Cu" "F.Mask" "F.Paste")
			(net "FM_SMB_1_ALERT_GPU_N")
		)
		(pad "2" smd circle
			(at 0.40005 0 90)
			(size 0 0)
			(layers "F.Cu" "F.Mask" "F.Paste")
			(net "GND")
		)
	)
	(footprint ""
		(layer "F.Cu")
		(at 331.055472 -396.146274)
		(property "Reference" "R611"
			(at 0 0 0)
			(layer "F.SilkS")
			(hide yes)
			(effects
				(font
					(size 1.27 1.27)
				)
			)
		)
		(property "Value" ""
			(at 0 0 0)
			(layer "F.Fab")
			(effects
				(font
					(size 1.27 1.27)
				)
			)
		)
		(duplicate_pad_numbers_are_jumpers no)
		(fp_line
			(start -0.32512 -0.175006)
			(end 0.32512 -0.175006)
			(stroke
				(width 0.1)
				(type default)
			)
			(layer "F.Fab")
		)
		(fp_line
			(start -0.32512 0.175006)
			(end -0.32512 -0.175006)
			(stroke
				(width 0.1)
				(type default)
			)
			(layer "F.Fab")
		)
		(fp_line
			(start 0.32512 -0.175006)
			(end 0.32512 0.175006)
			(stroke
				(width 0.1)
				(type default)
			)
			(layer "F.Fab")
		)
		(fp_line
			(start 0.32512 0.175006)
			(end -0.32512 0.175006)
			(stroke
				(width 0.1)
				(type default)
			)
			(layer "F.Fab")
		)
		(pad "1" smd rect
			(at -0.2667 0)
			(size 0.3048 0.381)
			(layers "F.Cu" "F.Mask" "F.Paste")
			(net "CLK_100M_RETIMER_CPU0_P1_R_DP")
		)
		(pad "2" smd rect
			(at 0.2667 0 180)
			(size 0.3048 0.381)
			(layers "F.Cu" "F.Mask" "F.Paste")
			(net "CLK_100M_RETIMER_CPU0_P1_DP")
		)
	)
	(footprint ""
		(layer "F.Cu")
		(at 29.226764 -388.931658 -90)
		(property "Reference" "PC6634_2"
			(at 0 0 270)
			(layer "F.SilkS")
			(hide yes)
			(effects
				(font
					(size 1.27 1.27)
				)
			)
		)
		(property "Value" ""
			(at 0 0 270)
			(layer "F.Fab")
			(effects
				(font
					(size 1.27 1.27)
				)
			)
		)
		(duplicate_pad_numbers_are_jumpers no)
		(fp_line
			(start -0.7874 0.4064)
			(end -0.7874 -0.4064)
			(stroke
				(width 0.1524)
				(type default)
			)
			(layer "F.SilkS")
		)
		(fp_line
			(start 0.7874 0.4064)
			(end -0.7874 0.4064)
			(stroke
				(width 0.1524)
				(type default)
			)
			(layer "F.SilkS")
		)
		(fp_line
			(start -0.7874 -0.4064)
			(end 0.7874 -0.4064)
			(stroke
				(width 0.1524)
				(type default)
			)
			(layer "F.SilkS")
		)
		(fp_line
			(start 0.7874 -0.4064)
			(end 0.7874 0.4064)
			(stroke
				(width 0.1524)
				(type default)
			)
			(layer "F.SilkS")
		)
		(fp_line
			(start -0.67945 0.3048)
			(end -0.67945 -0.305054)
			(stroke
				(width 0.1)
				(type default)
			)
			(layer "F.Fab")
		)
		(fp_line
			(start -0.12065 0.3048)
			(end -0.67945 0.3048)
			(stroke
				(width 0.1)
				(type default)
			)
			(layer "F.Fab")
		)
		(fp_line
			(start 0.120396 0.3048)
			(end 0.120396 0.2794)
			(stroke
				(width 0.1)
				(type default)
			)
			(layer "F.Fab")
		)
		(fp_line
			(start 0.67945 0.3048)
			(end 0.120396 0.3048)
			(stroke
				(width 0.1)
				(type default)
			)
			(layer "F.Fab")
		)
		(fp_line
			(start -0.12065 0.2794)
			(end -0.12065 0.3048)
			(stroke
				(width 0.1)
				(type default)
			)
			(layer "F.Fab")
		)
		(fp_line
			(start 0.120396 0.2794)
			(end -0.12065 0.2794)
			(stroke
				(width 0.1)
				(type default)
			)
			(layer "F.Fab")
		)
		(fp_line
			(start -0.12065 -0.2794)
			(end 0.12065 -0.2794)
			(stroke
				(width 0.1)
				(type default)
			)
			(layer "F.Fab")
		)
		(fp_line
			(start 0.12065 -0.2794)
			(end 0.12065 -0.3048)
			(stroke
				(width 0.1)
				(type default)
			)
			(layer "F.Fab")
		)
		(fp_line
			(start 0.12065 -0.3048)
			(end 0.67945 -0.3048)
			(stroke
				(width 0.1)
				(type default)
			)
			(layer "F.Fab")
		)
		(fp_line
			(start 0.67945 -0.3048)
			(end 0.67945 0.3048)
			(stroke
				(width 0.1)
				(type default)
			)
			(layer "F.Fab")
		)
		(fp_line
			(start -0.67945 -0.305054)
			(end -0.12065 -0.305054)
			(stroke
				(width 0.1)
				(type default)
			)
			(layer "F.Fab")
		)
		(fp_line
			(start -0.12065 -0.305054)
			(end -0.12065 -0.2794)
			(stroke
				(width 0.1)
				(type default)
			)
			(layer "F.Fab")
		)
		(pad "1" smd circle
			(at -0.40005 0 270)
			(size 0 0)
			(layers "F.Cu" "F.Mask" "F.Paste")
			(net "SW_P12V_AUX_P0V9_RETIMER_CPU1_FLT")
		)
		(pad "2" smd circle
			(at 0.40005 0 270)
			(size 0 0)
			(layers "F.Cu" "F.Mask" "F.Paste")
			(net "GND")
		)
	)
	(footprint ""
		(layer "F.Cu")
		(at 197.269608 -123.785376)
		(property "Reference" "R11667"
			(at 0 0 0)
			(layer "F.SilkS")
			(hide yes)
			(effects
				(font
					(size 1.27 1.27)
				)
			)
		)
		(property "Value" ""
			(at 0 0 0)
			(layer "F.Fab")
			(effects
				(font
					(size 1.27 1.27)
				)
			)
		)
		(duplicate_pad_numbers_are_jumpers no)
		(fp_line
			(start -0.7874 -0.4064)
			(end 0.7874 -0.4064)
			(stroke
				(width 0.1524)
				(type default)
			)
			(layer "F.SilkS")
		)
		(fp_line
			(start -0.7874 0.4064)
			(end -0.7874 -0.4064)
			(stroke
				(width 0.1524)
				(type default)
			)
			(layer "F.SilkS")
		)
		(fp_line
			(start 0.7874 -0.4064)
			(end 0.7874 0.4064)
			(stroke
				(width 0.1524)
				(type default)
			)
			(layer "F.SilkS")
		)
		(fp_line
			(start 0.7874 0.4064)
			(end -0.7874 0.4064)
			(stroke
				(width 0.1524)
				(type default)
			)
			(layer "F.SilkS")
		)
		(fp_line
			(start -0.67945 -0.305054)
			(end -0.12065 -0.305054)
			(stroke
				(width 0.1)
				(type default)
			)
			(layer "F.Fab")
		)
		(fp_line
			(start -0.67945 0.3048)
			(end -0.67945 -0.305054)
			(stroke
				(width 0.1)
				(type default)
			)
			(layer "F.Fab")
		)
		(fp_line
			(start -0.12065 -0.305054)
			(end -0.12065 -0.2794)
			(stroke
				(width 0.1)
				(type default)
			)
			(layer "F.Fab")
		)
		(fp_line
			(start -0.12065 -0.2794)
			(end 0.12065 -0.2794)
			(stroke
				(width 0.1)
				(type default)
			)
			(layer "F.Fab")
		)
		(fp_line
			(start -0.12065 0.2794)
			(end -0.12065 0.3048)
			(stroke
				(width 0.1)
				(type default)
			)
			(layer "F.Fab")
		)
		(fp_line
			(start -0.12065 0.3048)
			(end -0.67945 0.3048)
			(stroke
				(width 0.1)
				(type default)
			)
			(layer "F.Fab")
		)
		(fp_line
			(start 0.120396 0.2794)
			(end -0.12065 0.2794)
			(stroke
				(width 0.1)
				(type default)
			)
			(layer "F.Fab")
		)
		(fp_line
			(start 0.120396 0.3048)
			(end 0.120396 0.2794)
			(stroke
				(width 0.1)
				(type default)
			)
			(layer "F.Fab")
		)
		(fp_line
			(start 0.12065 -0.3048)
			(end 0.67945 -0.3048)
			(stroke
				(width 0.1)
				(type default)
			)
			(layer "F.Fab")
		)
		(fp_line
			(start 0.12065 -0.2794)
			(end 0.12065 -0.3048)
			(stroke
				(width 0.1)
				(type default)
			)
			(layer "F.Fab")
		)
		(fp_line
			(start 0.67945 -0.3048)
			(end 0.67945 0.3048)
			(stroke
				(width 0.1)
				(type default)
			)
			(layer "F.Fab")
		)
		(fp_line
			(start 0.67945 0.3048)
			(end 0.120396 0.3048)
			(stroke
				(width 0.1)
				(type default)
			)
			(layer "F.Fab")
		)
		(pad "1" smd circle
			(at -0.40005 0)
			(size 0 0)
			(layers "F.Cu" "F.Mask" "F.Paste")
			(net "FM_SMB_2_ALERT_GPU_ISO_R_N")
		)
		(pad "2" smd circle
			(at 0.40005 0)
			(size 0 0)
			(layers "F.Cu" "F.Mask" "F.Paste")
			(net "FM_SMB_2_ALERT_GPU_ISO_N")
		)
	)
	(footprint ""
		(layer "F.Cu")
		(at 117.895624 -258.405376 180)
		(property "Reference" "C2288"
			(at 0 0 180)
			(layer "F.SilkS")
			(hide yes)
			(effects
				(font
					(size 1.27 1.27)
				)
			)
		)
		(property "Value" ""
			(at 0 0 180)
			(layer "F.Fab")
			(effects
				(font
					(size 1.27 1.27)
				)
			)
		)
		(duplicate_pad_numbers_are_jumpers no)
		(fp_line
			(start 0.7874 0.4064)
			(end -0.7874 0.4064)
			(stroke
				(width 0.1524)
				(type default)
			)
			(layer "F.SilkS")
		)
		(fp_line
			(start 0.7874 -0.4064)
			(end 0.7874 0.4064)
			(stroke
				(width 0.1524)
				(type default)
			)
			(layer "F.SilkS")
		)
		(fp_line
			(start -0.7874 0.4064)
			(end -0.7874 -0.4064)
			(stroke
				(width 0.1524)
				(type default)
			)
			(layer "F.SilkS")
		)
		(fp_line
			(start -0.7874 -0.4064)
			(end 0.7874 -0.4064)
			(stroke
				(width 0.1524)
				(type default)
			)
			(layer "F.SilkS")
		)
		(fp_line
			(start 0.67945 0.3048)
			(end 0.120396 0.3048)
			(stroke
				(width 0.1)
				(type default)
			)
			(layer "F.Fab")
		)
		(fp_line
			(start 0.67945 -0.3048)
			(end 0.67945 0.3048)
			(stroke
				(width 0.1)
				(type default)
			)
			(layer "F.Fab")
		)
		(fp_line
			(start 0.12065 -0.2794)
			(end 0.12065 -0.3048)
			(stroke
				(width 0.1)
				(type default)
			)
			(layer "F.Fab")
		)
		(fp_line
			(start 0.12065 -0.3048)
			(end 0.67945 -0.3048)
			(stroke
				(width 0.1)
				(type default)
			)
			(layer "F.Fab")
		)
		(fp_line
			(start 0.120396 0.3048)
			(end 0.120396 0.2794)
			(stroke
				(width 0.1)
				(type default)
			)
			(layer "F.Fab")
		)
		(fp_line
			(start 0.120396 0.2794)
			(end -0.12065 0.2794)
			(stroke
				(width 0.1)
				(type default)
			)
			(layer "F.Fab")
		)
		(fp_line
			(start -0.12065 0.3048)
			(end -0.67945 0.3048)
			(stroke
				(width 0.1)
				(type default)
			)
			(layer "F.Fab")
		)
		(fp_line
			(start -0.12065 0.2794)
			(end -0.12065 0.3048)
			(stroke
				(width 0.1)
				(type default)
			)
			(layer "F.Fab")
		)
		(fp_line
			(start -0.12065 -0.2794)
			(end 0.12065 -0.2794)
			(stroke
				(width 0.1)
				(type default)
			)
			(layer "F.Fab")
		)
		(fp_line
			(start -0.12065 -0.305054)
			(end -0.12065 -0.2794)
			(stroke
				(width 0.1)
				(type default)
			)
			(layer "F.Fab")
		)
		(fp_line
			(start -0.67945 0.3048)
			(end -0.67945 -0.305054)
			(stroke
				(width 0.1)
				(type default)
			)
			(layer "F.Fab")
		)
		(fp_line
			(start -0.67945 -0.305054)
			(end -0.12065 -0.305054)
			(stroke
				(width 0.1)
				(type default)
			)
			(layer "F.Fab")
		)
		(pad "1" smd circle
			(at -0.40005 0 180)
			(size 0 0)
			(layers "F.Cu" "F.Mask" "F.Paste")
			(net "PVDDCR_SOC_P1")
		)
		(pad "2" smd circle
			(at 0.40005 0 180)
			(size 0 0)
			(layers "F.Cu" "F.Mask" "F.Paste")
			(net "GND")
		)
	)
	(footprint ""
		(layer "F.Cu")
		(at 305.819048 -45.005498)
		(property "Reference" "R3672"
			(at 0 0 0)
			(layer "F.SilkS")
			(hide yes)
			(effects
				(font
					(size 1.27 1.27)
				)
			)
		)
		(property "Value" ""
			(at 0 0 0)
			(layer "F.Fab")
			(effects
				(font
					(size 1.27 1.27)
				)
			)
		)
		(duplicate_pad_numbers_are_jumpers no)
		(fp_line
			(start -0.7874 -0.4064)
			(end 0.7874 -0.4064)
			(stroke
				(width 0.1524)
				(type default)
			)
			(layer "F.SilkS")
		)
		(fp_line
			(start -0.7874 0.4064)
			(end -0.7874 -0.4064)
			(stroke
				(width 0.1524)
				(type default)
			)
			(layer "F.SilkS")
		)
		(fp_line
			(start 0.7874 -0.4064)
			(end 0.7874 0.4064)
			(stroke
				(width 0.1524)
				(type default)
			)
			(layer "F.SilkS")
		)
		(fp_line
			(start 0.7874 0.4064)
			(end -0.7874 0.4064)
			(stroke
				(width 0.1524)
				(type default)
			)
			(layer "F.SilkS")
		)
		(fp_line
			(start -0.67945 -0.305054)
			(end -0.12065 -0.305054)
			(stroke
				(width 0.1)
				(type default)
			)
			(layer "F.Fab")
		)
		(fp_line
			(start -0.67945 0.3048)
			(end -0.67945 -0.305054)
			(stroke
				(width 0.1)
				(type default)
			)
			(layer "F.Fab")
		)
		(fp_line
			(start -0.12065 -0.305054)
			(end -0.12065 -0.2794)
			(stroke
				(width 0.1)
				(type default)
			)
			(layer "F.Fab")
		)
		(fp_line
			(start -0.12065 -0.2794)
			(end 0.12065 -0.2794)
			(stroke
				(width 0.1)
				(type default)
			)
			(layer "F.Fab")
		)
		(fp_line
			(start -0.12065 0.2794)
			(end -0.12065 0.3048)
			(stroke
				(width 0.1)
				(type default)
			)
			(layer "F.Fab")
		)
		(fp_line
			(start -0.12065 0.3048)
			(end -0.67945 0.3048)
			(stroke
				(width 0.1)
				(type default)
			)
			(layer "F.Fab")
		)
		(fp_line
			(start 0.120396 0.2794)
			(end -0.12065 0.2794)
			(stroke
				(width 0.1)
				(type default)
			)
			(layer "F.Fab")
		)
		(fp_line
			(start 0.120396 0.3048)
			(end 0.120396 0.2794)
			(stroke
				(width 0.1)
				(type default)
			)
			(layer "F.Fab")
		)
		(fp_line
			(start 0.12065 -0.3048)
			(end 0.67945 -0.3048)
			(stroke
				(width 0.1)
				(type default)
			)
			(layer "F.Fab")
		)
		(fp_line
			(start 0.12065 -0.2794)
			(end 0.12065 -0.3048)
			(stroke
				(width 0.1)
				(type default)
			)
			(layer "F.Fab")
		)
		(fp_line
			(start 0.67945 -0.3048)
			(end 0.67945 0.3048)
			(stroke
				(width 0.1)
				(type default)
			)
			(layer "F.Fab")
		)
		(fp_line
			(start 0.67945 0.3048)
			(end 0.120396 0.3048)
			(stroke
				(width 0.1)
				(type default)
			)
			(layer "F.Fab")
		)
		(pad "1" smd circle
			(at -0.40005 0)
			(size 0 0)
			(layers "F.Cu" "F.Mask" "F.Paste")
			(net "SMB_SCM_2_R4_SCL")
		)
		(pad "2" smd circle
			(at 0.40005 0)
			(size 0 0)
			(layers "F.Cu" "F.Mask" "F.Paste")
			(net "SMB_SEN_TIC_3V3AUX_SCL")
		)
	)
)
